# S9S_MB_2U (Grand Teton) — schematic netlist excerpt (pin names and nets, part order shuffled) for the footprints in the layout excerpt that follows; sources: Cadence DE-HDL packaged netlist, KiCad conversion of 03242023_DA0F0TMBIJ0_F0T_Motherboard_J_brd_V01_OCP.brd

R4574  Q_RES  0 5% EMPTY  pkg 0402LF  page 146 : A = PRSNT_CABLE_GPU_A1_N ; B = PRSNT_CABLE_GPU_A1_ISO_N
R4054  Q_RES  1K 1% CHIP  pkg 0402LF  page 225 : A = PD_GTL2014_BMC_JTAG_DIR_1 ; B = GND

(kicad_pcb
	(version 20260206)
	(generator "pcbnew")
	(generator_version "10.0")
	(general
		(thickness 1.6)
		(legacy_teardrops no)
	)
	(paper "A4")
	(title_block
		(title "03242023_DA0F0TMBIJ0_F0T_Motherboard_J_brd_V01_OCP.brd")
		(comment 1 "Grand Teton / footprints 2471-2472 of 6105")
	)
	(layers
		(0 "F.Cu" signal "TOP")
		(4 "In1.Cu" signal "GND")
		(6 "In2.Cu" signal "IN1")
		(8 "In3.Cu" signal "GND1")
		(10 "In4.Cu" signal "IN2")
		(12 "In5.Cu" signal "GND2")
		(14 "In6.Cu" signal "IN3")
		(16 "In7.Cu" signal "GND3")
		(18 "In8.Cu" signal "VCC")
		(20 "In9.Cu" signal "VCC1")
		(22 "In10.Cu" signal "GND4")
		(24 "In11.Cu" signal "IN4")
		(26 "In12.Cu" signal "GND5")
		(28 "In13.Cu" signal "IN5")
		(30 "In14.Cu" signal "GND6")
		(32 "In15.Cu" signal "IN6")
		(34 "In16.Cu" signal "GND7")
		(2 "B.Cu" signal "BOTTOM")
		(9 "F.Adhes" user "F.Adhesive")
		(11 "B.Adhes" user "B.Adhesive")
		(13 "F.Paste" user "Package Geometry/Pastemask Top")
		(15 "B.Paste" user "Package Geometry/Pastemask Bottom")
		(5 "F.SilkS" user "Ref Des/Silkscreen Top")
		(7 "B.SilkS" user "Ref Des/Silkscreen Bottom")
		(1 "F.Mask" user "Board Geometry/Soldermask Top")
		(3 "B.Mask" user "Board Geometry/Soldermask Bottom")
		(17 "Dwgs.User" user "User.Drawings")
		(19 "Cmts.User" user "User.Comments")
		(21 "Eco1.User" user "User.Eco1")
		(23 "Eco2.User" user "User.Eco2")
		(25 "Edge.Cuts" user "Board Geometry/Outline")
		(27 "Margin" user)
		(31 "F.CrtYd" user "Package Geometry/Place Bound Top")
		(29 "B.CrtYd" user "Package Geometry/Place Bound Bottom")
		(35 "F.Fab" user "Ref Des/Assembly Top")
		(33 "B.Fab" user "Ref Des/Assembly Bottom")
	)
	(footprint ""
		(layer "F.Cu")
		(at 295.25595 -417.2204)
		(property "Reference" "R4574"
			(at 0 0 0)
			(layer "F.SilkS")
			(hide yes)
			(effects
				(font
					(size 1.27 1.27)
				)
			)
		)
		(property "Value" ""
			(at 0 0 0)
			(layer "F.Fab")
			(effects
				(font
					(size 1.27 1.27)
				)
			)
		)
		(duplicate_pad_numbers_are_jumpers no)
		(fp_line
			(start -0.7874 -0.4064)
			(end 0.7874 -0.4064)
			(stroke
				(width 0.1524)
				(type default)
			)
			(layer "F.SilkS")
		)
		(fp_line
			(start -0.7874 0.4064)
			(end -0.7874 -0.4064)
			(stroke
				(width 0.1524)
				(type default)
			)
			(layer "F.SilkS")
		)
		(fp_line
			(start 0.7874 -0.4064)
			(end 0.7874 0.4064)
			(stroke
				(width 0.1524)
				(type default)
			)
			(layer "F.SilkS")
		)
		(fp_line
			(start 0.7874 0.4064)
			(end -0.7874 0.4064)
			(stroke
				(width 0.1524)
				(type default)
			)
			(layer "F.SilkS")
		)
		(fp_line
			(start -0.67945 -0.305054)
			(end -0.12065 -0.305054)
			(stroke
				(width 0.1)
				(type default)
			)
			(layer "F.Fab")
		)
		(fp_line
			(start -0.67945 0.3048)
			(end -0.67945 -0.305054)
			(stroke
				(width 0.1)
				(type default)
			)
			(layer "F.Fab")
		)
		(fp_line
			(start -0.12065 -0.305054)
			(end -0.12065 -0.2794)
			(stroke
				(width 0.1)
				(type default)
			)
			(layer "F.Fab")
		)
		(fp_line
			(start -0.12065 -0.2794)
			(end 0.12065 -0.2794)
			(stroke
				(width 0.1)
				(type default)
			)
			(layer "F.Fab")
		)
		(fp_line
			(start -0.12065 0.2794)
			(end -0.12065 0.3048)
			(stroke
				(width 0.1)
				(type default)
			)
			(layer "F.Fab")
		)
		(fp_line
			(start -0.12065 0.3048)
			(end -0.67945 0.3048)
			(stroke
				(width 0.1)
				(type default)
			)
			(layer "F.Fab")
		)
		(fp_line
			(start 0.120396 0.2794)
			(end -0.12065 0.2794)
			(stroke
				(width 0.1)
				(type default)
			)
			(layer "F.Fab")
		)
		(fp_line
			(start 0.120396 0.3048)
			(end 0.120396 0.2794)
			(stroke
				(width 0.1)
				(type default)
			)
			(layer "F.Fab")
		)
		(fp_line
			(start 0.12065 -0.3048)
			(end 0.67945 -0.3048)
			(stroke
				(width 0.1)
				(type default)
			)
			(layer "F.Fab")
		)
		(fp_line
			(start 0.12065 -0.2794)
			(end 0.12065 -0.3048)
			(stroke
				(width 0.1)
				(type default)
			)
			(layer "F.Fab")
		)
		(fp_line
			(start 0.67945 -0.3048)
			(end 0.67945 0.3048)
			(stroke
				(width 0.1)
				(type default)
			)
			(layer "F.Fab")
		)
		(fp_line
			(start 0.67945 0.3048)
			(end 0.120396 0.3048)
			(stroke
				(width 0.1)
				(type default)
			)
			(layer "F.Fab")
		)
		(pad "1" smd circle
			(at -0.40005 0)
			(size 0 0)
			(layers "F.Cu" "F.Mask" "F.Paste")
			(net "PRSNT_CABLE_GPU_A1_N")
		)
		(pad "2" smd circle
			(at 0.40005 0)
			(size 0 0)
			(layers "F.Cu" "F.Mask" "F.Paste")
			(net "PRSNT_CABLE_GPU_A1_ISO_N")
		)
	)
	(footprint ""
		(layer "F.Cu")
		(at 127.804926 -119.810784 90)
		(property "Reference" "R4054"
			(at 0 0 90)
			(layer "F.SilkS")
			(hide yes)
			(effects
				(font
					(size 1.27 1.27)
				)
			)
		)
		(property "Value" ""
			(at 0 0 90)
			(layer "F.Fab")
			(effects
				(font
					(size 1.27 1.27)
				)
			)
		)
		(duplicate_pad_numbers_are_jumpers no)
		(fp_line
			(start 0.7874 -0.4064)
			(end 0.7874 0.4064)
			(stroke
				(width 0.1524)
				(type default)
			)
			(layer "F.SilkS")
		)
		(fp_line
			(start -0.7874 -0.4064)
			(end 0.7874 -0.4064)
			(stroke
				(width 0.1524)
				(type default)
			)
			(layer "F.SilkS")
		)
		(fp_line
			(start 0.7874 0.4064)
			(end -0.7874 0.4064)
			(stroke
				(width 0.1524)
				(type default)
			)
			(layer "F.SilkS")
		)
		(fp_line
			(start -0.7874 0.4064)
			(end -0.7874 -0.4064)
			(stroke
				(width 0.1524)
				(type default)
			)
			(layer "F.SilkS")
		)
		(fp_line
			(start -0.12065 -0.305054)
			(end -0.12065 -0.2794)
			(stroke
				(width 0.1)
				(type default)
			)
			(layer "F.Fab")
		)
		(fp_line
			(start -0.67945 -0.305054)
			(end -0.12065 -0.305054)
			(stroke
				(width 0.1)
				(type default)
			)
			(layer "F.Fab")
		)
		(fp_line
			(start 0.67945 -0.3048)
			(end 0.67945 0.3048)
			(stroke
				(width 0.1)
				(type default)
			)
			(layer "F.Fab")
		)
		(fp_line
			(start 0.12065 -0.3048)
			(end 0.67945 -0.3048)
			(stroke
				(width 0.1)
				(type default)
			)
			(layer "F.Fab")
		)
		(fp_line
			(start 0.12065 -0.2794)
			(end 0.12065 -0.3048)
			(stroke
				(width 0.1)
				(type default)
			)
			(layer "F.Fab")
		)
		(fp_line
			(start -0.12065 -0.2794)
			(end 0.12065 -0.2794)
			(stroke
				(width 0.1)
				(type default)
			)
			(layer "F.Fab")
		)
		(fp_line
			(start 0.120396 0.2794)
			(end -0.12065 0.2794)
			(stroke
				(width 0.1)
				(type default)
			)
			(layer "F.Fab")
		)
		(fp_line
			(start -0.12065 0.2794)
			(end -0.12065 0.3048)
			(stroke
				(width 0.1)
				(type default)
			)
			(layer "F.Fab")
		)
		(fp_line
			(start 0.67945 0.3048)
			(end 0.120396 0.3048)
			(stroke
				(width 0.1)
				(type default)
			)
			(layer "F.Fab")
		)
		(fp_line
			(start 0.120396 0.3048)
			(end 0.120396 0.2794)
			(stroke
				(width 0.1)
				(type default)
			)
			(layer "F.Fab")
		)
		(fp_line
			(start -0.12065 0.3048)
			(end -0.67945 0.3048)
			(stroke
				(width 0.1)
				(type default)
			)
			(layer "F.Fab")
		)
		(fp_line
			(start -0.67945 0.3048)
			(end -0.67945 -0.305054)
			(stroke
				(width 0.1)
				(type default)
			)
			(layer "F.Fab")
		)
		(pad "1" smd circle
			(at -0.40005 0 90)
			(size 0 0)
			(layers "F.Cu" "F.Mask" "F.Paste")
			(net "PD_GTL2014_BMC_JTAG_DIR_1")
		)
		(pad "2" smd circle
			(at 0.40005 0 90)
			(size 0 0)
			(layers "F.Cu" "F.Mask" "F.Paste")
			(net "GND")
		)
	)
)
